(kicad_pcb
	(version 20260206)
	(generator "pcbnew")
	(generator_version "10.0")
	(general
		(thickness 1.6)
		(legacy_teardrops no)
	)
	(paper "A4")
	(title_block
		(title "Bryce Canyon_R.DPB_16317-1_OCP.brd")
		(comment 1 "Bryce Canyon / footprints 1871-1873 of 2099")
	)
	(layers
		(0 "F.Cu" signal "TOP")
		(4 "In1.Cu" signal "L2GND")
		(6 "In2.Cu" signal "L3")
		(8 "In3.Cu" signal "L4VCC")
		(10 "In4.Cu" signal "L5VCC")
		(12 "In5.Cu" signal "L6")
		(14 "In6.Cu" signal "L7GND")
		(2 "B.Cu" signal "BOTTOM")
		(9 "F.Adhes" user "F.Adhesive")
		(11 "B.Adhes" user "B.Adhesive")
		(13 "F.Paste" user "Package Geometry/Pastemask Top")
		(15 "B.Paste" user "Package Geometry/Pastemask Bottom")
		(5 "F.SilkS" user "Ref Des/Silkscreen Top")
		(7 "B.SilkS" user "Ref Des/Silkscreen Bottom")
		(1 "F.Mask" user "Board Geometry/Soldermask Top")
		(3 "B.Mask" user "Board Geometry/Soldermask Bottom")
		(17 "Dwgs.User" user "User.Drawings")
		(19 "Cmts.User" user "User.Comments")
		(21 "Eco1.User" user "User.Eco1")
		(23 "Eco2.User" user "User.Eco2")
		(25 "Edge.Cuts" user "Board Geometry/Outline")
		(27 "Margin" user)
		(31 "F.CrtYd" user "Package Geometry/Place Bound Top")
		(29 "B.CrtYd" user "Package Geometry/Place Bound Bottom")
		(35 "F.Fab" user "Ref Des/Assembly Top")
		(33 "B.Fab" user "Ref Des/Assembly Bottom")
	)
	(footprint ""
		(layer "F.Cu")
		(at 59.749944 -143.91005 -90)
		(property "Reference" "HDDSAS13"
			(at 0 0 270)
			(layer "F.SilkS")
			(hide yes)
			(effects
				(font
					(size 1.27 1.27)
				)
			)
		)
		(property "Value" "SKT-SAS15P-14P-45-GP"
			(at -20.7645 -8.9789 270)
			(unlocked yes)
			(layer "F.Fab")
			(hide yes)
			(effects
				(font
					(size 1.016 1.016)
					(thickness 0.1524)
				)
			)
		)
		(property "Device Type" "10120818-001C-TRLF"
			(at -20.7645 -10.5029 270)
			(unlocked yes)
			(layer "F.Fab")
			(hide yes)
			(effects
				(font
					(size 1.016 1.016)
					(thickness 0.1524)
				)
			)
		)
		(duplicate_pad_numbers_are_jumpers no)
		(fp_line
			(start 1.651 4.2926)
			(end 1.651 3.0099)
			(stroke
				(width 0.1524)
				(type default)
			)
			(layer "F.SilkS")
		)
		(fp_line
			(start 8.509 4.2926)
			(end 1.651 4.2926)
			(stroke
				(width 0.1524)
				(type default)
			)
			(layer "F.SilkS")
		)
		(fp_line
			(start -23.4188 3.0099)
			(end -23.4188 -3.2512)
			(stroke
				(width 0.1524)
				(type default)
			)
			(layer "F.SilkS")
		)
		(fp_line
			(start 1.651 3.0099)
			(end -23.4188 3.0099)
			(stroke
				(width 0.1524)
				(type default)
			)
			(layer "F.SilkS")
		)
		(fp_line
			(start 8.509 3.0099)
			(end 8.509 4.2926)
			(stroke
				(width 0.1524)
				(type default)
			)
			(layer "F.SilkS")
		)
		(fp_line
			(start 23.4188 3.0099)
			(end 8.509 3.0099)
			(stroke
				(width 0.1524)
				(type default)
			)
			(layer "F.SilkS")
		)
		(fp_line
			(start -23.4188 -3.2512)
			(end 23.4188 -3.2512)
			(stroke
				(width 0.1524)
				(type default)
			)
			(layer "F.SilkS")
		)
		(fp_line
			(start 23.4188 -3.2512)
			(end 23.4188 3.0099)
			(stroke
				(width 0.1524)
				(type default)
			)
			(layer "F.SilkS")
		)
		(fp_line
			(start 15.5067 -3.3401)
			(end 16.2687 -3.3401)
			(stroke
				(width 0.3302)
				(type default)
			)
			(layer "F.SilkS")
		)
		(fp_poly
			(pts
				(xy 15.868904 -3.230372) (xy 16.503904 -3.865372) (xy 15.233904 -3.865372)
			)
			(stroke
				(width 0)
				(type default)
			)
			(fill yes)
			(layer "F.SilkS")
		)
		(fp_poly
			(pts
				(xy -22.8727 -2.7559) (xy 22.8727 -2.7559) (xy 22.8727 2.7559) (xy 8.255 2.7559) (xy 8.255 3.5179)
				(xy 1.905 3.5179) (xy 1.905 2.7559) (xy -22.8727 2.7559)
			)
			(stroke
				(width 0)
				(type default)
			)
			(fill no)
			(layer "F.CrtYd")
		)
		(fp_poly
			(pts
				(xy 1.397 4.5466) (xy 1.397 3.2639) (xy -23.6728 3.2639) (xy -23.6728 -3.5052) (xy 23.6728 -3.5052)
				(xy 23.6728 -0.00635) (xy 22.8727 -0.00635) (xy 22.8727 -2.7559) (xy -22.8727 -2.7559) (xy -22.8727 2.7559)
				(xy 1.905 2.7559) (xy 1.905 3.5179) (xy 8.255 3.5179) (xy 8.255 2.7559) (xy 22.8727 2.7559) (xy 22.8727 0.00635)
				(xy 23.6728 0.00635) (xy 23.6728 3.2639) (xy 8.763 3.2639) (xy 8.763 4.5466)
			)
			(stroke
				(width 0)
				(type default)
			)
			(fill no)
			(layer "F.CrtYd")
		)
		(fp_poly
			(pts
				(xy 1.397 4.5466) (xy 1.397 3.2639) (xy -23.6728 3.2639) (xy -23.6728 -3.5052) (xy 23.6728 -3.5052)
				(xy 23.6728 3.2639) (xy 8.763 3.2639) (xy 8.763 4.5466)
			)
			(stroke
				(width 0)
				(type default)
			)
			(fill no)
			(layer "F.Fab")
		)
		(pad "" np_thru_hole circle
			(at -18.874994 0 270)
			(size 0.254 0.254)
			(drill 1.3462)
			(layers "*.Cu" "*.Mask")
			(clearance 0.9017)
			(thermal_gap 0.9017)
		)
		(pad "" np_thru_hole circle
			(at 18.874994 0 270)
			(size 0.254 0.254)
			(drill 0.9398)
			(layers "*.Cu" "*.Mask")
			(clearance 0.6985)
			(thermal_gap 0.6985)
		)
		(pad "G1" smd rect
			(at 21.874988 0 270)
			(size 2.5908 2.5908)
			(layers "F.Cu" "F.Mask" "F.Paste")
			(net "GND")
		)
		(pad "G2" smd rect
			(at -21.874988 0 270)
			(size 2.5908 2.5908)
			(layers "F.Cu" "F.Mask" "F.Paste")
			(net "GND")
		)
		(pad "P1" smd rect
			(at 1.905 -1.82499 270)
			(size 0.6096 2.3622)
			(layers "F.Cu" "F.Mask" "F.Paste")
			(net "Net_1739")
		)
		(pad "P2" smd rect
			(at 0.635 -1.82499 270)
			(size 0.6096 2.3622)
			(layers "F.Cu" "F.Mask" "F.Paste")
			(net "Net_1740")
		)
		(pad "P3" smd rect
			(at -0.635 -1.82499 270)
			(size 0.6096 2.3622)
			(layers "F.Cu" "F.Mask" "F.Paste")
			(net "Net_1741")
		)
		(pad "P4" smd rect
			(at -1.905 -1.82499 270)
			(size 0.6096 2.3622)
			(layers "F.Cu" "F.Mask" "F.Paste")
			(net "GND")
		)
		(pad "P5" smd rect
			(at -3.175 -1.82499 270)
			(size 0.6096 2.3622)
			(layers "F.Cu" "F.Mask" "F.Paste")
			(net "HDD_PRSNT_13")
		)
		(pad "P6" smd rect
			(at -4.445 -1.82499 270)
			(size 0.6096 2.3622)
			(layers "F.Cu" "F.Mask" "F.Paste")
			(net "GND")
		)
		(pad "P7" smd rect
			(at -5.715 -1.82499 270)
			(size 0.6096 2.3622)
			(layers "F.Cu" "F.Mask" "F.Paste")
			(net "5V_PRE_13")
		)
		(pad "P8" smd rect
			(at -6.985 -1.82499 270)
			(size 0.6096 2.3622)
			(layers "F.Cu" "F.Mask" "F.Paste")
			(net "P5V_HDD13")
		)
		(pad "P9" smd rect
			(at -8.255 -1.82499 270)
			(size 0.6096 2.3622)
			(layers "F.Cu" "F.Mask" "F.Paste")
			(net "P5V_HDD13")
		)
		(pad "P10" smd rect
			(at -9.525 -1.82499 270)
			(size 0.6096 2.3622)
			(layers "F.Cu" "F.Mask" "F.Paste")
			(net "GND")
		)
		(pad "P11" smd rect
			(at -10.795 -1.82499 270)
			(size 0.6096 2.3622)
			(layers "F.Cu" "F.Mask" "F.Paste")
			(net "ACT_HDD_13")
		)
		(pad "P12" smd rect
			(at -12.065 -1.82499 270)
			(size 0.6096 2.3622)
			(layers "F.Cu" "F.Mask" "F.Paste")
			(net "GND")
		)
		(pad "P13" smd rect
			(at -13.335 -1.82499 270)
			(size 0.6096 2.3622)
			(layers "F.Cu" "F.Mask" "F.Paste")
			(net "12V_PRE_13")
		)
		(pad "P14" smd rect
			(at -14.605 -1.82499 270)
			(size 0.6096 2.3622)
			(layers "F.Cu" "F.Mask" "F.Paste")
			(net "P12V_HDD13")
		)
		(pad "P15" smd rect
			(at -15.875 -1.82499 270)
			(size 0.6096 2.3622)
			(layers "F.Cu" "F.Mask" "F.Paste")
			(net "P12V_HDD13")
		)
		(pad "S1" smd rect
			(at 15.875 -1.82499 270)
			(size 0.6096 2.3622)
			(layers "F.Cu" "F.Mask" "F.Paste")
			(net "GND")
		)
		(pad "S2" smd rect
			(at 14.605 -1.82499 270)
			(size 0.6096 2.3622)
			(layers "F.Cu" "F.Mask" "F.Paste")
			(net "SAS_HDD_RX_P13")
		)
		(pad "S3" smd rect
			(at 13.335 -1.82499 270)
			(size 0.6096 2.3622)
			(layers "F.Cu" "F.Mask" "F.Paste")
			(net "SAS_HDD_RX_N13")
		)
		(pad "S4" smd rect
			(at 12.065 -1.82499 270)
			(size 0.6096 2.3622)
			(layers "F.Cu" "F.Mask" "F.Paste")
			(net "GND")
		)
		(pad "S5" smd rect
			(at 10.795 -1.82499 270)
			(size 0.6096 2.3622)
			(layers "F.Cu" "F.Mask" "F.Paste")
			(net "PHY_DRV_B_TO_SCC_B_13_DN")
		)
		(pad "S6" smd rect
			(at 9.525 -1.82499 270)
			(size 0.6096 2.3622)
			(layers "F.Cu" "F.Mask" "F.Paste")
			(net "PHY_DRV_B_TO_SCC_B_13_DP")
		)
		(pad "S7" smd rect
			(at 8.255 -1.82499 270)
			(size 0.6096 2.3622)
			(layers "F.Cu" "F.Mask" "F.Paste")
			(net "GND")
		)
		(pad "S8" smd rect
			(at 7.480046 2.845054 270)
			(size 0.508 2.3622)
			(layers "F.Cu" "F.Mask" "F.Paste")
			(net "GND")
		)
		(pad "S9" smd rect
			(at 6.679946 2.845054 270)
			(size 0.508 2.3622)
			(layers "F.Cu" "F.Mask" "F.Paste")
			(net "Net_436")
		)
		(pad "S10" smd rect
			(at 5.8801 2.845054 270)
			(size 0.508 2.3622)
			(layers "F.Cu" "F.Mask" "F.Paste")
			(net "Net_328")
		)
		(pad "S11" smd rect
			(at 5.08 2.845054 270)
			(size 0.508 2.3622)
			(layers "F.Cu" "F.Mask" "F.Paste")
			(net "GND")
		)
		(pad "S12" smd rect
			(at 4.2799 2.845054 270)
			(size 0.508 2.3622)
			(layers "F.Cu" "F.Mask" "F.Paste")
			(net "Net_364")
		)
		(pad "S13" smd rect
			(at 3.480054 2.845054 270)
			(size 0.508 2.3622)
			(layers "F.Cu" "F.Mask" "F.Paste")
			(net "Net_400")
		)
		(pad "S14" smd rect
			(at 2.679954 2.845054 270)
			(size 0.508 2.3622)
			(layers "F.Cu" "F.Mask" "F.Paste")
			(net "GND")
		)
		(zone
			(layer "F.Cu")
			(hatch none 0.5)
			(connect_pads
				(clearance 0)
			)
			(min_thickness 0.25)
			(keepout
				(tracks not_allowed)
				(vias allowed)
				(pads allowed)
				(copperpour not_allowed)
				(footprints allowed)
			)
			(placement
				(enabled no)
				(sheetname "")
			)
			(fill
				(thermal_gap 0.5)
				(thermal_bridge_width 0.5)
				(island_removal_mode 0)
			)
			(polygon
				(pts
					(xy 63.407544 -160.64865) (xy 56.333644 -160.64865) (xy 56.333644 -167.58285) (xy 57.438544 -167.58285)
					(xy 57.438544 -163.46805) (xy 62.061344 -163.46805) (xy 62.061344 -167.58285) (xy 63.407544 -167.58285)
				)
			)
		)
		(zone
			(layer "F.Cu")
			(hatch none 0.5)
			(connect_pads
				(clearance 0)
			)
			(min_thickness 0.25)
			(keepout
				(tracks allowed)
				(vias not_allowed)
				(pads allowed)
				(copperpour not_allowed)
				(footprints allowed)
			)
			(placement
				(enabled no)
				(sheetname "")
			)
			(fill
				(thermal_gap 0.5)
				(thermal_bridge_width 0.5)
				(island_removal_mode 0)
			)
			(polygon
				(pts
					(xy 63.407544 -160.64865) (xy 56.333644 -160.64865) (xy 56.333644 -167.58285) (xy 57.438544 -167.58285)
					(xy 57.438544 -163.46805) (xy 62.061344 -163.46805) (xy 62.061344 -167.58285) (xy 63.407544 -167.58285)
				)
			)
		)
		(zone
			(layer "F.Cu")
			(hatch none 0.5)
			(connect_pads
				(clearance 0)
			)
			(min_thickness 0.25)
			(keepout
				(tracks allowed)
				(vias not_allowed)
				(pads allowed)
				(copperpour not_allowed)
				(footprints allowed)
			)
			(placement
				(enabled no)
				(sheetname "")
			)
			(fill
				(thermal_gap 0.5)
				(thermal_bridge_width 0.5)
				(island_removal_mode 0)
			)
			(polygon
				(pts
					(xy 63.407544 -127.17145) (xy 56.333644 -127.17145) (xy 56.333644 -120.23725) (xy 57.438544 -120.23725)
					(xy 57.438544 -124.35205) (xy 62.061344 -124.35205) (xy 62.061344 -120.23725) (xy 63.407544 -120.23725)
				)
			)
		)
		(zone
			(layer "F.Cu")
			(hatch none 0.5)
			(connect_pads
				(clearance 0)
			)
			(min_thickness 0.25)
			(keepout
				(tracks not_allowed)
				(vias allowed)
				(pads allowed)
				(copperpour not_allowed)
				(footprints allowed)
			)
			(placement
				(enabled no)
				(sheetname "")
			)
			(fill
				(thermal_gap 0.5)
				(thermal_bridge_width 0.5)
				(island_removal_mode 0)
			)
			(polygon
				(pts
					(xy 63.407544 -127.17145) (xy 56.333644 -127.17145) (xy 56.333644 -120.23725) (xy 57.438544 -120.23725)
					(xy 57.438544 -124.35205) (xy 62.061344 -124.35205) (xy 62.061344 -120.23725) (xy 63.407544 -120.23725)
				)
			)
		)
		(zone
			(layers "F.Cu" "B.Cu" "In1.Cu" "In2.Cu" "In3.Cu" "In4.Cu" "In5.Cu" "In6.Cu")
			(hatch none 0.5)
			(connect_pads
				(clearance 0)
			)
			(min_thickness 0.25)
			(keepout
				(tracks not_allowed)
				(vias allowed)
				(pads allowed)
				(copperpour not_allowed)
				(footprints allowed)
			)
			(placement
				(enabled no)
				(sheetname "")
			)
			(fill
				(thermal_gap 0.5)
				(thermal_bridge_width 0.5)
				(island_removal_mode 0)
			)
			(polygon
				(pts
					(arc
						(start 60.524644 -125.035056)
						(mid 58.975244 -125.035056)
						(end 60.524644 -125.035056)
					)
				)
			)
		)
		(zone
			(layers "F.Cu" "B.Cu" "In1.Cu" "In2.Cu" "In3.Cu" "In4.Cu" "In5.Cu" "In6.Cu")
			(hatch none 0.5)
			(connect_pads
				(clearance 0)
			)
			(min_thickness 0.25)
			(keepout
				(tracks not_allowed)
				(vias allowed)
				(pads allowed)
				(copperpour not_allowed)
				(footprints allowed)
			)
			(placement
				(enabled no)
				(sheetname "")
			)
			(fill
				(thermal_gap 0.5)
				(thermal_bridge_width 0.5)
				(island_removal_mode 0)
			)
			(polygon
				(pts
					(arc
						(start 60.727844 -162.785044)
						(mid 58.772044 -162.785044)
						(end 60.727844 -162.785044)
					)
				)
			)
		)
	)
	(footprint ""
		(layer "F.Cu")
		(at 473.583 -214.249)
		(property "Reference" "R380"
			(at 0 0 0)
			(layer "F.SilkS")
			(hide yes)
			(effects
				(font
					(size 1.27 1.27)
				)
			)
		)
		(property "Value" "91R3F-1-GP"
			(at -0.0254 -2.5146 0)
			(unlocked yes)
			(layer "F.Fab")
			(hide yes)
			(effects
				(font
					(size 1.016 1.016)
					(thickness 0.1524)
				)
			)
		)
		(property "Device Type" "R603H22"
			(at -0.0254 -4.0386 0)
			(unlocked yes)
			(layer "F.Fab")
			(hide yes)
			(effects
				(font
					(size 1.016 1.016)
					(thickness 0.1524)
				)
			)
		)
		(duplicate_pad_numbers_are_jumpers no)
		(fp_line
			(start -0.4826 0)
			(end -0.2032 0)
			(stroke
				(width 0.2032)
				(type default)
			)
			(layer "F.SilkS")
		)
		(fp_line
			(start 0.2032 0)
			(end 0.4826 0)
			(stroke
				(width 0.2032)
				(type default)
			)
			(layer "F.SilkS")
		)
		(fp_rect
			(start -0.5842 1.3335)
			(end 0.5842 -1.3335)
			(stroke
				(width 0)
				(type default)
			)
			(fill no)
			(layer "F.CrtYd")
		)
		(fp_rect
			(start -0.5842 1.3335)
			(end 0.5842 -1.3335)
			(stroke
				(width 0)
				(type default)
			)
			(fill no)
			(layer "F.Fab")
		)
		(pad "1" smd custom
			(at 0 -0.762)
			(size 0.2159 0.2159)
			(layers "F.Cu" "F.Mask" "F.Paste")
			(net "P5V_B_3")
			(options
				(clearance outline)
				(anchor circle)
			)
			(primitives
				(gr_poly
					(pts
						(arc
							(start -0.3302 -0.4318)
							(mid -0.402042 -0.402042)
							(end -0.4318 -0.3302)
						)
						(arc
							(start -0.4318 0.3302)
							(mid -0.402042 0.402042)
							(end -0.3302 0.4318)
						)
						(arc
							(start 0.3302 0.4318)
							(mid 0.402042 0.402042)
							(end 0.4318 0.3302)
						)
						(arc
							(start 0.4318 -0.3302)
							(mid 0.402042 -0.402042)
							(end 0.3302 -0.4318)
						)
					)
					(width 0)
					(fill yes)
				)
			)
		)
		(pad "2" smd custom
			(at 0 0.762)
			(size 0.2159 0.2159)
			(layers "F.Cu" "F.Mask" "F.Paste")
			(net "DRV_ACT_11")
			(options
				(clearance outline)
				(anchor circle)
			)
			(primitives
				(gr_poly
					(pts
						(arc
							(start -0.3302 -0.4318)
							(mid -0.402042 -0.402042)
							(end -0.4318 -0.3302)
						)
						(arc
							(start -0.4318 0.3302)
							(mid -0.402042 0.402042)
							(end -0.3302 0.4318)
						)
						(arc
							(start 0.3302 0.4318)
							(mid 0.402042 0.402042)
							(end 0.4318 0.3302)
						)
						(arc
							(start 0.4318 -0.3302)
							(mid 0.402042 -0.402042)
							(end 0.3302 -0.4318)
						)
					)
					(width 0)
					(fill yes)
				)
			)
		)
	)
	(footprint ""
		(layer "F.Cu")
		(at 180.975 -19.177)
		(property "Reference" "R745"
			(at 0 0 0)
			(layer "F.SilkS")
			(hide yes)
			(effects
				(font
					(size 1.27 1.27)
				)
			)
		)
		(property "Value" "1KR2F-3-GP"
			(at 0.064008 -3.993896 0)
			(unlocked yes)
			(layer "F.Fab")
			(hide yes)
			(effects
				(font
					(size 1.016 1.016)
					(thickness 0.1524)
				)
			)
		)
		(property "Device Type" "R402H16"
			(at 0.064008 -5.517896 0)
			(unlocked yes)
			(layer "F.Fab")
			(hide yes)
			(effects
				(font
					(size 1.016 1.016)
					(thickness 0.1524)
				)
			)
		)
		(duplicate_pad_numbers_are_jumpers no)
		(fp_line
			(start -0.508 -0.9398)
			(end -0.508 0.9398)
			(stroke
				(width 0.1524)
				(type default)
			)
			(layer "F.SilkS")
		)
		(fp_line
			(start 0.508 -0.9398)
			(end -0.508 -0.9398)
			(stroke
				(width 0.1524)
				(type default)
			)
			(layer "F.SilkS")
		)
		(fp_rect
			(start -0.508 0.9398)
			(end 0.508 -0.9398)
			(stroke
				(width 0)
				(type default)
			)
			(fill no)
			(layer "F.CrtYd")
		)
		(fp_rect
			(start -0.508 0.9398)
			(end 0.508 -0.9398)
			(stroke
				(width 0)
				(type default)
			)
			(fill no)
			(layer "F.Fab")
		)
		(pad "1" smd custom
			(at 0 -0.4445)
			(size 0.1397 0.1397)
			(layers "F.Cu" "F.Mask" "F.Paste")
			(net "P3V3_STBY_B")
			(options
				(clearance outline)
				(anchor circle)
			)
			(primitives
				(gr_poly
					(pts
						(arc
							(start -0.1778 -0.2794)
							(mid -0.249642 -0.249642)
							(end -0.2794 -0.1778)
						)
						(arc
							(start -0.2794 0.1778)
							(mid -0.249642 0.249642)
							(end -0.1778 0.2794)
						)
						(arc
							(start 0.1778 0.2794)
							(mid 0.249642 0.249642)
							(end 0.2794 0.1778)
						)
						(arc
							(start 0.2794 -0.1778)
							(mid 0.249642 -0.249642)
							(end 0.1778 -0.2794)
						)
					)
					(width 0)
					(fill yes)
				)
			)
		)
		(pad "2" smd custom
			(at 0 0.4445)
			(size 0.1397 0.1397)
			(layers "F.Cu" "F.Mask" "F.Paste")
			(net "SW_PWR_R_HDD29")
			(options
				(clearance outline)
				(anchor circle)
			)
			(primitives
				(gr_poly
					(pts
						(arc
							(start -0.1778 -0.2794)
							(mid -0.249642 -0.249642)
							(end -0.2794 -0.1778)
						)
						(arc
							(start -0.2794 0.1778)
							(mid -0.249642 0.249642)
							(end -0.1778 0.2794)
						)
						(arc
							(start 0.1778 0.2794)
							(mid 0.249642 0.249642)
							(end 0.2794 0.1778)
						)
						(arc
							(start 0.2794 -0.1778)
							(mid 0.249642 -0.249642)
							(end 0.1778 -0.2794)
						)
					)
					(width 0)
					(fill yes)
				)
			)
		)
	)
)
